# T6G (Grand Teton) — schematic netlist excerpt (pin names and nets, part order shuffled) for the footprints in the layout excerpt that follows; sources: Cadence DE-HDL packaged netlist, KiCad conversion of 04192023_DAF0TMB3IC0_F0TG_MB_C_brd_V02_OCP.brd

R4173  Q_RES  100K 1% EMPTY  pkg 0402LF  page 130 : A = P3V3_AUX ; B = UART_BMC_BIC_R_BUF_RX
PC6612_1  Q_CAP  1UF 25V 10% X6S  pkg C0402  page 365 : A = SW_P12V_AUX_P0V9_RETIMER_CPU1_FLT ; B = GND

(kicad_pcb
	(version 20260206)
	(generator "pcbnew")
	(generator_version "10.0")
	(general
		(thickness 1.6)
		(legacy_teardrops no)
	)
	(paper "A4")
	(title_block
		(title "04192023_DAF0TMB3IC0_F0TG_MB_C_brd_V02_OCP.brd")
		(comment 1 "Grand Teton / footprints 3445-3446 of 8354")
	)
	(layers
		(0 "F.Cu" signal "TOP")
		(4 "In1.Cu" signal "GND")
		(6 "In2.Cu" signal "IN1")
		(8 "In3.Cu" signal "GND1")
		(10 "In4.Cu" signal "IN2")
		(12 "In5.Cu" signal "GND2")
		(14 "In6.Cu" signal "IN3")
		(16 "In7.Cu" signal "GND3")
		(18 "In8.Cu" signal "VCC")
		(20 "In9.Cu" signal "VCC1")
		(22 "In10.Cu" signal "GND4")
		(24 "In11.Cu" signal "IN4")
		(26 "In12.Cu" signal "GND5")
		(28 "In13.Cu" signal "IN5")
		(30 "In14.Cu" signal "GND6")
		(32 "In15.Cu" signal "IN6")
		(34 "In16.Cu" signal "GND7")
		(2 "B.Cu" signal "BOTTOM")
		(9 "F.Adhes" user "F.Adhesive")
		(11 "B.Adhes" user "B.Adhesive")
		(13 "F.Paste" user "Package Geometry/Pastemask Top")
		(15 "B.Paste" user "Package Geometry/Pastemask Bottom")
		(5 "F.SilkS" user "Ref Des/Silkscreen Top")
		(7 "B.SilkS" user "Ref Des/Silkscreen Bottom")
		(1 "F.Mask" user "Board Geometry/Soldermask Top")
		(3 "B.Mask" user "Board Geometry/Soldermask Bottom")
		(17 "Dwgs.User" user "User.Drawings")
		(19 "Cmts.User" user "User.Comments")
		(21 "Eco1.User" user "User.Eco1")
		(23 "Eco2.User" user "User.Eco2")
		(25 "Edge.Cuts" user "Board Geometry/Outline")
		(27 "Margin" user)
		(31 "F.CrtYd" user "Package Geometry/Place Bound Top")
		(29 "B.CrtYd" user "Package Geometry/Place Bound Bottom")
		(35 "F.Fab" user "Ref Des/Assembly Top")
		(33 "B.Fab" user "Ref Des/Assembly Bottom")
	)
	(footprint ""
		(layer "F.Cu")
		(at 20.148042 -389.007858 -90)
		(property "Reference" "PC6612_1"
			(at 0 0 270)
			(layer "F.SilkS")
			(hide yes)
			(effects
				(font
					(size 1.27 1.27)
				)
			)
		)
		(property "Value" ""
			(at 0 0 270)
			(layer "F.Fab")
			(effects
				(font
					(size 1.27 1.27)
				)
			)
		)
		(duplicate_pad_numbers_are_jumpers no)
		(fp_line
			(start -0.7874 0.4064)
			(end -0.7874 -0.4064)
			(stroke
				(width 0.1524)
				(type default)
			)
			(layer "F.SilkS")
		)
		(fp_line
			(start 0.7874 0.4064)
			(end -0.7874 0.4064)
			(stroke
				(width 0.1524)
				(type default)
			)
			(layer "F.SilkS")
		)
		(fp_line
			(start -0.7874 -0.4064)
			(end 0.7874 -0.4064)
			(stroke
				(width 0.1524)
				(type default)
			)
			(layer "F.SilkS")
		)
		(fp_line
			(start 0.7874 -0.4064)
			(end 0.7874 0.4064)
			(stroke
				(width 0.1524)
				(type default)
			)
			(layer "F.SilkS")
		)
		(fp_line
			(start -0.67945 0.3048)
			(end -0.67945 -0.305054)
			(stroke
				(width 0.1)
				(type default)
			)
			(layer "F.Fab")
		)
		(fp_line
			(start -0.12065 0.3048)
			(end -0.67945 0.3048)
			(stroke
				(width 0.1)
				(type default)
			)
			(layer "F.Fab")
		)
		(fp_line
			(start 0.120396 0.3048)
			(end 0.120396 0.2794)
			(stroke
				(width 0.1)
				(type default)
			)
			(layer "F.Fab")
		)
		(fp_line
			(start 0.67945 0.3048)
			(end 0.120396 0.3048)
			(stroke
				(width 0.1)
				(type default)
			)
			(layer "F.Fab")
		)
		(fp_line
			(start -0.12065 0.2794)
			(end -0.12065 0.3048)
			(stroke
				(width 0.1)
				(type default)
			)
			(layer "F.Fab")
		)
		(fp_line
			(start 0.120396 0.2794)
			(end -0.12065 0.2794)
			(stroke
				(width 0.1)
				(type default)
			)
			(layer "F.Fab")
		)
		(fp_line
			(start -0.12065 -0.2794)
			(end 0.12065 -0.2794)
			(stroke
				(width 0.1)
				(type default)
			)
			(layer "F.Fab")
		)
		(fp_line
			(start 0.12065 -0.2794)
			(end 0.12065 -0.3048)
			(stroke
				(width 0.1)
				(type default)
			)
			(layer "F.Fab")
		)
		(fp_line
			(start 0.12065 -0.3048)
			(end 0.67945 -0.3048)
			(stroke
				(width 0.1)
				(type default)
			)
			(layer "F.Fab")
		)
		(fp_line
			(start 0.67945 -0.3048)
			(end 0.67945 0.3048)
			(stroke
				(width 0.1)
				(type default)
			)
			(layer "F.Fab")
		)
		(fp_line
			(start -0.67945 -0.305054)
			(end -0.12065 -0.305054)
			(stroke
				(width 0.1)
				(type default)
			)
			(layer "F.Fab")
		)
		(fp_line
			(start -0.12065 -0.305054)
			(end -0.12065 -0.2794)
			(stroke
				(width 0.1)
				(type default)
			)
			(layer "F.Fab")
		)
		(pad "1" smd circle
			(at -0.40005 0 270)
			(size 0 0)
			(layers "F.Cu" "F.Mask" "F.Paste")
			(net "SW_P12V_AUX_P0V9_RETIMER_CPU1_FLT")
		)
		(pad "2" smd circle
			(at 0.40005 0 270)
			(size 0 0)
			(layers "F.Cu" "F.Mask" "F.Paste")
			(net "GND")
		)
	)
	(footprint ""
		(layer "F.Cu")
		(at 360.76001 -418.329618 180)
		(property "Reference" "R4173"
			(at 0 0 180)
			(layer "F.SilkS")
			(hide yes)
			(effects
				(font
					(size 1.27 1.27)
				)
			)
		)
		(property "Value" ""
			(at 0 0 180)
			(layer "F.Fab")
			(effects
				(font
					(size 1.27 1.27)
				)
			)
		)
		(duplicate_pad_numbers_are_jumpers no)
		(fp_line
			(start 0.7874 0.4064)
			(end -0.7874 0.4064)
			(stroke
				(width 0.1524)
				(type default)
			)
			(layer "F.SilkS")
		)
		(fp_line
			(start 0.7874 -0.4064)
			(end 0.7874 0.4064)
			(stroke
				(width 0.1524)
				(type default)
			)
			(layer "F.SilkS")
		)
		(fp_line
			(start -0.7874 0.4064)
			(end -0.7874 -0.4064)
			(stroke
				(width 0.1524)
				(type default)
			)
			(layer "F.SilkS")
		)
		(fp_line
			(start -0.7874 -0.4064)
			(end 0.7874 -0.4064)
			(stroke
				(width 0.1524)
				(type default)
			)
			(layer "F.SilkS")
		)
		(fp_line
			(start 0.67945 0.3048)
			(end 0.120396 0.3048)
			(stroke
				(width 0.1)
				(type default)
			)
			(layer "F.Fab")
		)
		(fp_line
			(start 0.67945 -0.3048)
			(end 0.67945 0.3048)
			(stroke
				(width 0.1)
				(type default)
			)
			(layer "F.Fab")
		)
		(fp_line
			(start 0.12065 -0.2794)
			(end 0.12065 -0.3048)
			(stroke
				(width 0.1)
				(type default)
			)
			(layer "F.Fab")
		)
		(fp_line
			(start 0.12065 -0.3048)
			(end 0.67945 -0.3048)
			(stroke
				(width 0.1)
				(type default)
			)
			(layer "F.Fab")
		)
		(fp_line
			(start 0.120396 0.3048)
			(end 0.120396 0.2794)
			(stroke
				(width 0.1)
				(type default)
			)
			(layer "F.Fab")
		)
		(fp_line
			(start 0.120396 0.2794)
			(end -0.12065 0.2794)
			(stroke
				(width 0.1)
				(type default)
			)
			(layer "F.Fab")
		)
		(fp_line
			(start -0.12065 0.3048)
			(end -0.67945 0.3048)
			(stroke
				(width 0.1)
				(type default)
			)
			(layer "F.Fab")
		)
		(fp_line
			(start -0.12065 0.2794)
			(end -0.12065 0.3048)
			(stroke
				(width 0.1)
				(type default)
			)
			(layer "F.Fab")
		)
		(fp_line
			(start -0.12065 -0.2794)
			(end 0.12065 -0.2794)
			(stroke
				(width 0.1)
				(type default)
			)
			(layer "F.Fab")
		)
		(fp_line
			(start -0.12065 -0.305054)
			(end -0.12065 -0.2794)
			(stroke
				(width 0.1)
				(type default)
			)
			(layer "F.Fab")
		)
		(fp_line
			(start -0.67945 0.3048)
			(end -0.67945 -0.305054)
			(stroke
				(width 0.1)
				(type default)
			)
			(layer "F.Fab")
		)
		(fp_line
			(start -0.67945 -0.305054)
			(end -0.12065 -0.305054)
			(stroke
				(width 0.1)
				(type default)
			)
			(layer "F.Fab")
		)
		(pad "1" smd circle
			(at -0.40005 0 180)
			(size 0 0)
			(layers "F.Cu" "F.Mask" "F.Paste")
			(net "P3V3_AUX")
		)
		(pad "2" smd circle
			(at 0.40005 0 180)
			(size 0 0)
			(layers "F.Cu" "F.Mask" "F.Paste")
			(net "UART_BMC_BIC_R_BUF_RX")
		)
	)
)
